# S9S_MB_2U (Grand Teton) — schematic netlist excerpt (pin names and nets, part order shuffled) for the footprints in the layout excerpt that follows; sources: Cadence DE-HDL packaged netlist, KiCad conversion of 03242023_DA0F0TMBIJ0_F0T_Motherboard_J_brd_V01_OCP.brd

PC506_P1_5  Q_CAP  3300PF 50V 10% X7R  pkg 0402  page 287 : A = SW_P12V_PVCCIN_CPU1_FLT ; B = GND
PC1232  Q_CAP  10UF 16V 10% X6S  pkg C0805  page 263 : A = SW_P1V8_PCH_AUX_FLT ; B = GND
PD102  SCHOTTKY_AC  B340A-13-F IC  pkg D2010XF  page 156 : A = GND ; C = P12V_OCP_SFF

(kicad_pcb
	(version 20260206)
	(generator "pcbnew")
	(generator_version "10.0")
	(general
		(thickness 1.6)
		(legacy_teardrops no)
	)
	(paper "A4")
	(title_block
		(title "03242023_DA0F0TMBIJ0_F0T_Motherboard_J_brd_V01_OCP.brd")
		(comment 1 "Grand Teton / footprints 2040-2042 of 6105")
	)
	(layers
		(0 "F.Cu" signal "TOP")
		(4 "In1.Cu" signal "GND")
		(6 "In2.Cu" signal "IN1")
		(8 "In3.Cu" signal "GND1")
		(10 "In4.Cu" signal "IN2")
		(12 "In5.Cu" signal "GND2")
		(14 "In6.Cu" signal "IN3")
		(16 "In7.Cu" signal "GND3")
		(18 "In8.Cu" signal "VCC")
		(20 "In9.Cu" signal "VCC1")
		(22 "In10.Cu" signal "GND4")
		(24 "In11.Cu" signal "IN4")
		(26 "In12.Cu" signal "GND5")
		(28 "In13.Cu" signal "IN5")
		(30 "In14.Cu" signal "GND6")
		(32 "In15.Cu" signal "IN6")
		(34 "In16.Cu" signal "GND7")
		(2 "B.Cu" signal "BOTTOM")
		(9 "F.Adhes" user "F.Adhesive")
		(11 "B.Adhes" user "B.Adhesive")
		(13 "F.Paste" user "Package Geometry/Pastemask Top")
		(15 "B.Paste" user "Package Geometry/Pastemask Bottom")
		(5 "F.SilkS" user "Ref Des/Silkscreen Top")
		(7 "B.SilkS" user "Ref Des/Silkscreen Bottom")
		(1 "F.Mask" user "Board Geometry/Soldermask Top")
		(3 "B.Mask" user "Board Geometry/Soldermask Bottom")
		(17 "Dwgs.User" user "User.Drawings")
		(19 "Cmts.User" user "User.Comments")
		(21 "Eco1.User" user "User.Eco1")
		(23 "Eco2.User" user "User.Eco2")
		(25 "Edge.Cuts" user "Board Geometry/Outline")
		(27 "Margin" user)
		(31 "F.CrtYd" user "Package Geometry/Place Bound Top")
		(29 "B.CrtYd" user "Package Geometry/Place Bound Bottom")
		(35 "F.Fab" user "Ref Des/Assembly Top")
		(33 "B.Fab" user "Ref Des/Assembly Bottom")
	)
	(footprint ""
		(layer "F.Cu")
		(at 133.816852 -340.064598)
		(property "Reference" "PC506_P1_5"
			(at 0 0 0)
			(layer "F.SilkS")
			(hide yes)
			(effects
				(font
					(size 1.27 1.27)
				)
			)
		)
		(property "Value" ""
			(at 0 0 0)
			(layer "F.Fab")
			(effects
				(font
					(size 1.27 1.27)
				)
			)
		)
		(duplicate_pad_numbers_are_jumpers no)
		(fp_line
			(start -0.7874 -0.4064)
			(end 0.7874 -0.4064)
			(stroke
				(width 0.1524)
				(type default)
			)
			(layer "F.SilkS")
		)
		(fp_line
			(start -0.7874 0.4064)
			(end -0.7874 -0.4064)
			(stroke
				(width 0.1524)
				(type default)
			)
			(layer "F.SilkS")
		)
		(fp_line
			(start 0.7874 -0.4064)
			(end 0.7874 0.4064)
			(stroke
				(width 0.1524)
				(type default)
			)
			(layer "F.SilkS")
		)
		(fp_line
			(start 0.7874 0.4064)
			(end -0.7874 0.4064)
			(stroke
				(width 0.1524)
				(type default)
			)
			(layer "F.SilkS")
		)
		(fp_line
			(start -0.67945 -0.305054)
			(end -0.12065 -0.305054)
			(stroke
				(width 0.1)
				(type default)
			)
			(layer "F.Fab")
		)
		(fp_line
			(start -0.67945 0.3048)
			(end -0.67945 -0.305054)
			(stroke
				(width 0.1)
				(type default)
			)
			(layer "F.Fab")
		)
		(fp_line
			(start -0.12065 -0.305054)
			(end -0.12065 -0.2794)
			(stroke
				(width 0.1)
				(type default)
			)
			(layer "F.Fab")
		)
		(fp_line
			(start -0.12065 -0.2794)
			(end 0.12065 -0.2794)
			(stroke
				(width 0.1)
				(type default)
			)
			(layer "F.Fab")
		)
		(fp_line
			(start -0.12065 0.2794)
			(end -0.12065 0.3048)
			(stroke
				(width 0.1)
				(type default)
			)
			(layer "F.Fab")
		)
		(fp_line
			(start -0.12065 0.3048)
			(end -0.67945 0.3048)
			(stroke
				(width 0.1)
				(type default)
			)
			(layer "F.Fab")
		)
		(fp_line
			(start 0.120396 0.2794)
			(end -0.12065 0.2794)
			(stroke
				(width 0.1)
				(type default)
			)
			(layer "F.Fab")
		)
		(fp_line
			(start 0.120396 0.3048)
			(end 0.120396 0.2794)
			(stroke
				(width 0.1)
				(type default)
			)
			(layer "F.Fab")
		)
		(fp_line
			(start 0.12065 -0.3048)
			(end 0.67945 -0.3048)
			(stroke
				(width 0.1)
				(type default)
			)
			(layer "F.Fab")
		)
		(fp_line
			(start 0.12065 -0.2794)
			(end 0.12065 -0.3048)
			(stroke
				(width 0.1)
				(type default)
			)
			(layer "F.Fab")
		)
		(fp_line
			(start 0.67945 -0.3048)
			(end 0.67945 0.3048)
			(stroke
				(width 0.1)
				(type default)
			)
			(layer "F.Fab")
		)
		(fp_line
			(start 0.67945 0.3048)
			(end 0.120396 0.3048)
			(stroke
				(width 0.1)
				(type default)
			)
			(layer "F.Fab")
		)
		(pad "1" smd circle
			(at -0.40005 0)
			(size 0 0)
			(layers "F.Cu" "F.Mask" "F.Paste")
			(net "SW_P12V_PVCCIN_CPU1_FLT")
		)
		(pad "2" smd circle
			(at 0.40005 0)
			(size 0 0)
			(layers "F.Cu" "F.Mask" "F.Paste")
			(net "GND")
		)
	)
	(footprint ""
		(layer "F.Cu")
		(at 455.228452 -15.503398 180)
		(property "Reference" "PD102"
			(at -2.299716 -2.168652 0)
			(unlocked yes)
			(layer "F.SilkS")
			(effects
				(font
					(size 0.7874 0.5842)
					(thickness 0.1524)
				)
				(justify left)
			)
		)
		(property "Value" ""
			(at 0 0 180)
			(layer "F.Fab")
			(effects
				(font
					(size 1.27 1.27)
				)
			)
		)
		(duplicate_pad_numbers_are_jumpers no)
		(fp_line
			(start 4.107942 1.459992)
			(end -3.400044 1.459992)
			(stroke
				(width 0.1524)
				(type default)
			)
			(layer "F.SilkS")
		)
		(fp_line
			(start 4.107942 -1.459992)
			(end 4.107942 1.459992)
			(stroke
				(width 0.1524)
				(type default)
			)
			(layer "F.SilkS")
		)
		(fp_line
			(start -3.400044 1.459992)
			(end -3.400044 -1.459992)
			(stroke
				(width 0.1524)
				(type default)
			)
			(layer "F.SilkS")
		)
		(fp_line
			(start -3.400044 -1.459992)
			(end 4.107942 -1.459992)
			(stroke
				(width 0.1524)
				(type default)
			)
			(layer "F.SilkS")
		)
		(fp_rect
			(start 4.107942 -1.459992)
			(end 3.308096 1.459992)
			(stroke
				(width 0)
				(type default)
			)
			(fill yes)
			(layer "F.SilkS")
		)
		(fp_line
			(start 2.29997 1.459992)
			(end -2.29997 1.459992)
			(stroke
				(width 0.1)
				(type default)
			)
			(layer "F.Fab")
		)
		(fp_line
			(start 2.29997 -1.459992)
			(end 2.29997 1.459992)
			(stroke
				(width 0.1)
				(type default)
			)
			(layer "F.Fab")
		)
		(fp_line
			(start -2.29997 1.459992)
			(end -2.29997 -1.459992)
			(stroke
				(width 0.1)
				(type default)
			)
			(layer "F.Fab")
		)
		(fp_line
			(start -2.29997 -1.459992)
			(end 2.29997 -1.459992)
			(stroke
				(width 0.1)
				(type default)
			)
			(layer "F.Fab")
		)
		(fp_text user "-"
			(at 5.4102 0.29845 0)
			(unlocked yes)
			(layer "F.SilkS")
			(effects
				(font
					(size 1.905 1.4224)
					(thickness 0.1524)
				)
				(justify left)
			)
		)
		(fp_text user "+"
			(at -4.7752 -0.12065 180)
			(unlocked yes)
			(layer "F.SilkS")
			(effects
				(font
					(size 1.905 1.4224)
					(thickness 0.1524)
				)
				(justify left)
			)
		)
		(fp_text user "-"
			(at 5.4102 0.29845 0)
			(unlocked yes)
			(layer "F.Fab")
			(effects
				(font
					(size 1.905 1.4224)
					(thickness 0.1524)
				)
				(justify left)
			)
		)
		(fp_text user "+"
			(at -4.7752 -0.12065 180)
			(unlocked yes)
			(layer "F.Fab")
			(effects
				(font
					(size 1.905 1.4224)
					(thickness 0.1524)
				)
				(justify left)
			)
		)
		(pad "A" smd rect
			(at -1.999996 0 270)
			(size 1.7018 2.5146)
			(layers "F.Cu" "F.Mask" "F.Paste")
			(net "GND")
		)
		(pad "C" smd rect
			(at 1.999996 0 270)
			(size 1.7018 2.5146)
			(layers "F.Cu" "F.Mask" "F.Paste")
			(net "P12V_OCP_SFF")
		)
	)
	(footprint ""
		(layer "F.Cu")
		(at 389.902192 -76.171044 90)
		(property "Reference" "PC1232"
			(at 0 0 90)
			(layer "F.SilkS")
			(hide yes)
			(effects
				(font
					(size 1.27 1.27)
				)
			)
		)
		(property "Value" ""
			(at 0 0 90)
			(layer "F.Fab")
			(effects
				(font
					(size 1.27 1.27)
				)
			)
		)
		(duplicate_pad_numbers_are_jumpers no)
		(fp_line
			(start 1.524 -0.762)
			(end 1.524 0.762)
			(stroke
				(width 0.1524)
				(type default)
			)
			(layer "F.SilkS")
		)
		(fp_line
			(start -1.524 -0.762)
			(end 1.524 -0.762)
			(stroke
				(width 0.1524)
				(type default)
			)
			(layer "F.SilkS")
		)
		(fp_line
			(start 1.524 0.762)
			(end -1.524 0.762)
			(stroke
				(width 0.1524)
				(type default)
			)
			(layer "F.SilkS")
		)
		(fp_line
			(start -1.524 0.762)
			(end -1.524 -0.762)
			(stroke
				(width 0.1524)
				(type default)
			)
			(layer "F.SilkS")
		)
		(fp_line
			(start 1.1049 -0.724916)
			(end -1.1049 -0.724916)
			(stroke
				(width 0.1)
				(type default)
			)
			(layer "F.Fab")
		)
		(fp_line
			(start -1.1049 -0.724916)
			(end -1.1049 0.724916)
			(stroke
				(width 0.1)
				(type default)
			)
			(layer "F.Fab")
		)
		(fp_line
			(start 1.1049 0.724916)
			(end 1.1049 -0.724916)
			(stroke
				(width 0.1)
				(type default)
			)
			(layer "F.Fab")
		)
		(fp_line
			(start -1.1049 0.724916)
			(end 1.1049 0.724916)
			(stroke
				(width 0.1)
				(type default)
			)
			(layer "F.Fab")
		)
		(pad "1" smd rect
			(at -0.889 0 270)
			(size 1.016 1.27)
			(layers "F.Cu" "F.Mask" "F.Paste")
			(net "SW_P1V8_PCH_AUX_FLT")
		)
		(pad "2" smd rect
			(at 0.889 0 270)
			(size 1.016 1.27)
			(layers "F.Cu" "F.Mask" "F.Paste")
			(net "GND")
		)
	)
)
